# SCM (Grand Teton) — schematic netlist excerpt (pin names and nets, part order shuffled) for the footprints in the layout excerpt that follows; sources: Cadence DE-HDL packaged netlist, KiCad conversion of 12092022_DA0F0TMDCD0_F0T_Management_Board_D_brd_V3_OCP.brd

R312  Q_RES  47K 1% CHIP  pkg 0402LF  page 12 : A = RST_BMC_LPC_ESPI_N ; B = GND
R797  Q_RES  2.87K 1% CHIP  pkg 0402LF  page 15 : A = PGPPA_BMC_AUX ; B = PGPPA_BMC_AUX_SENSOR

(kicad_pcb
	(version 20260206)
	(generator "pcbnew")
	(generator_version "10.0")
	(general
		(thickness 1.6)
		(legacy_teardrops no)
	)
	(paper "A4")
	(title_block
		(title "12092022_DA0F0TMDCD0_F0T_Management_Board_D_brd_V3_OCP.brd")
		(comment 1 "Grand Teton / footprints 953-954 of 1440")
	)
	(layers
		(0 "F.Cu" signal "TOP")
		(4 "In1.Cu" signal "GND")
		(6 "In2.Cu" signal "IN1")
		(8 "In3.Cu" signal "GND1")
		(10 "In4.Cu" signal "IN2")
		(12 "In5.Cu" signal "VCC")
		(14 "In6.Cu" signal "VCC1")
		(16 "In7.Cu" signal "IN3")
		(18 "In8.Cu" signal "GND2")
		(20 "In9.Cu" signal "IN4")
		(22 "In10.Cu" signal "GND3")
		(2 "B.Cu" signal "BOTTOM")
		(9 "F.Adhes" user "F.Adhesive")
		(11 "B.Adhes" user "B.Adhesive")
		(13 "F.Paste" user "Package Geometry/Pastemask Top")
		(15 "B.Paste" user "Package Geometry/Pastemask Bottom")
		(5 "F.SilkS" user "Ref Des/Silkscreen Top")
		(7 "B.SilkS" user "Ref Des/Silkscreen Bottom")
		(1 "F.Mask" user "Board Geometry/Soldermask Top")
		(3 "B.Mask" user "Board Geometry/Soldermask Bottom")
		(17 "Dwgs.User" user "User.Drawings")
		(19 "Cmts.User" user "User.Comments")
		(21 "Eco1.User" user "User.Eco1")
		(23 "Eco2.User" user "User.Eco2")
		(25 "Edge.Cuts" user "Board Geometry/Outline")
		(27 "Margin" user)
		(31 "F.CrtYd" user "Package Geometry/Place Bound Top")
		(29 "B.CrtYd" user "Package Geometry/Place Bound Bottom")
		(35 "F.Fab" user "Ref Des/Assembly Top")
		(33 "B.Fab" user "Ref Des/Assembly Bottom")
	)
	(footprint ""
		(layer "B.Cu")
		(at 65.405 -69.977 90)
		(property "Reference" "R312"
			(at 0 0 90)
			(layer "B.SilkS")
			(hide yes)
			(effects
				(font
					(size 1.27 1.27)
				)
				(justify mirror)
			)
		)
		(property "Value" ""
			(at 0 0 90)
			(layer "B.Fab")
			(effects
				(font
					(size 1.27 1.27)
				)
				(justify mirror)
			)
		)
		(duplicate_pad_numbers_are_jumpers no)
		(fp_line
			(start 0.7874 -0.4064)
			(end -0.7874 -0.4064)
			(stroke
				(width 0.1524)
				(type default)
			)
			(layer "B.SilkS")
		)
		(fp_line
			(start -0.7874 -0.4064)
			(end -0.7874 0.4064)
			(stroke
				(width 0.1524)
				(type default)
			)
			(layer "B.SilkS")
		)
		(fp_line
			(start 0.7874 0.4064)
			(end 0.7874 -0.4064)
			(stroke
				(width 0.1524)
				(type default)
			)
			(layer "B.SilkS")
		)
		(fp_line
			(start -0.7874 0.4064)
			(end 0.7874 0.4064)
			(stroke
				(width 0.1524)
				(type default)
			)
			(layer "B.SilkS")
		)
		(fp_line
			(start 0.67945 -0.305054)
			(end 0.12065 -0.305054)
			(stroke
				(width 0.1)
				(type default)
			)
			(layer "B.Fab")
		)
		(fp_line
			(start 0.12065 -0.305054)
			(end 0.12065 -0.2794)
			(stroke
				(width 0.1)
				(type default)
			)
			(layer "B.Fab")
		)
		(fp_line
			(start -0.12065 -0.3048)
			(end -0.67945 -0.3048)
			(stroke
				(width 0.1)
				(type default)
			)
			(layer "B.Fab")
		)
		(fp_line
			(start -0.67945 -0.3048)
			(end -0.67945 0.3048)
			(stroke
				(width 0.1)
				(type default)
			)
			(layer "B.Fab")
		)
		(fp_line
			(start 0.12065 -0.2794)
			(end -0.12065 -0.2794)
			(stroke
				(width 0.1)
				(type default)
			)
			(layer "B.Fab")
		)
		(fp_line
			(start -0.12065 -0.2794)
			(end -0.12065 -0.3048)
			(stroke
				(width 0.1)
				(type default)
			)
			(layer "B.Fab")
		)
		(fp_line
			(start 0.12065 0.2794)
			(end 0.12065 0.3048)
			(stroke
				(width 0.1)
				(type default)
			)
			(layer "B.Fab")
		)
		(fp_line
			(start -0.120396 0.2794)
			(end 0.12065 0.2794)
			(stroke
				(width 0.1)
				(type default)
			)
			(layer "B.Fab")
		)
		(fp_line
			(start 0.67945 0.3048)
			(end 0.67945 -0.305054)
			(stroke
				(width 0.1)
				(type default)
			)
			(layer "B.Fab")
		)
		(fp_line
			(start 0.12065 0.3048)
			(end 0.67945 0.3048)
			(stroke
				(width 0.1)
				(type default)
			)
			(layer "B.Fab")
		)
		(fp_line
			(start -0.120396 0.3048)
			(end -0.120396 0.2794)
			(stroke
				(width 0.1)
				(type default)
			)
			(layer "B.Fab")
		)
		(fp_line
			(start -0.67945 0.3048)
			(end -0.120396 0.3048)
			(stroke
				(width 0.1)
				(type default)
			)
			(layer "B.Fab")
		)
		(pad "1" smd circle
			(at 0.40005 0 270)
			(size 0 0)
			(layers "B.Cu" "B.Mask" "B.Paste")
			(net "RST_BMC_LPC_ESPI_N")
		)
		(pad "2" smd circle
			(at -0.40005 0 270)
			(size 0 0)
			(layers "B.Cu" "B.Mask" "B.Paste")
			(net "GND")
		)
	)
	(footprint ""
		(layer "B.Cu")
		(at 59.662822 -72.113394)
		(property "Reference" "R797"
			(at 0 0 0)
			(layer "B.SilkS")
			(hide yes)
			(effects
				(font
					(size 1.27 1.27)
				)
				(justify mirror)
			)
		)
		(property "Value" ""
			(at 0 0 0)
			(layer "B.Fab")
			(effects
				(font
					(size 1.27 1.27)
				)
				(justify mirror)
			)
		)
		(duplicate_pad_numbers_are_jumpers no)
		(fp_line
			(start -0.7874 -0.4064)
			(end -0.7874 0.4064)
			(stroke
				(width 0.1524)
				(type default)
			)
			(layer "B.SilkS")
		)
		(fp_line
			(start -0.7874 0.4064)
			(end 0.7874 0.4064)
			(stroke
				(width 0.1524)
				(type default)
			)
			(layer "B.SilkS")
		)
		(fp_line
			(start 0.7874 -0.4064)
			(end -0.7874 -0.4064)
			(stroke
				(width 0.1524)
				(type default)
			)
			(layer "B.SilkS")
		)
		(fp_line
			(start 0.7874 0.4064)
			(end 0.7874 -0.4064)
			(stroke
				(width 0.1524)
				(type default)
			)
			(layer "B.SilkS")
		)
		(fp_line
			(start -0.67945 -0.3048)
			(end -0.67945 0.3048)
			(stroke
				(width 0.1)
				(type default)
			)
			(layer "B.Fab")
		)
		(fp_line
			(start -0.67945 0.3048)
			(end -0.120396 0.3048)
			(stroke
				(width 0.1)
				(type default)
			)
			(layer "B.Fab")
		)
		(fp_line
			(start -0.12065 -0.3048)
			(end -0.67945 -0.3048)
			(stroke
				(width 0.1)
				(type default)
			)
			(layer "B.Fab")
		)
		(fp_line
			(start -0.12065 -0.2794)
			(end -0.12065 -0.3048)
			(stroke
				(width 0.1)
				(type default)
			)
			(layer "B.Fab")
		)
		(fp_line
			(start -0.120396 0.2794)
			(end 0.12065 0.2794)
			(stroke
				(width 0.1)
				(type default)
			)
			(layer "B.Fab")
		)
		(fp_line
			(start -0.120396 0.3048)
			(end -0.120396 0.2794)
			(stroke
				(width 0.1)
				(type default)
			)
			(layer "B.Fab")
		)
		(fp_line
			(start 0.12065 -0.305054)
			(end 0.12065 -0.2794)
			(stroke
				(width 0.1)
				(type default)
			)
			(layer "B.Fab")
		)
		(fp_line
			(start 0.12065 -0.2794)
			(end -0.12065 -0.2794)
			(stroke
				(width 0.1)
				(type default)
			)
			(layer "B.Fab")
		)
		(fp_line
			(start 0.12065 0.2794)
			(end 0.12065 0.3048)
			(stroke
				(width 0.1)
				(type default)
			)
			(layer "B.Fab")
		)
		(fp_line
			(start 0.12065 0.3048)
			(end 0.67945 0.3048)
			(stroke
				(width 0.1)
				(type default)
			)
			(layer "B.Fab")
		)
		(fp_line
			(start 0.67945 -0.305054)
			(end 0.12065 -0.305054)
			(stroke
				(width 0.1)
				(type default)
			)
			(layer "B.Fab")
		)
		(fp_line
			(start 0.67945 0.3048)
			(end 0.67945 -0.305054)
			(stroke
				(width 0.1)
				(type default)
			)
			(layer "B.Fab")
		)
		(pad "1" smd circle
			(at 0.40005 0 180)
			(size 0 0)
			(layers "B.Cu" "B.Mask" "B.Paste")
			(net "PGPPA_BMC_AUX")
		)
		(pad "2" smd circle
			(at -0.40005 0 180)
			(size 0 0)
			(layers "B.Cu" "B.Mask" "B.Paste")
			(net "PGPPA_BMC_AUX_SENSOR")
		)
	)
)
